.HEADER
BOARD_FILE 3.0 "Creo Elements/Pro 5.0 M210" 2017/02/17.18:57:07 3
16369-SC                                MM        
.END_HEADER
.BOARD_OUTLINE  MCAD
1.60000             
         0             7.88500            -6.20000             0.00000
         0             7.88500            -0.20000             0.00000
         0             8.38500             0.30000           -90.00000
         0            50.71500             0.30000             0.00000
         0            51.21500            -0.20000           -90.00000
         0            51.21500            -6.20000             0.00000
         0            51.71500            -6.70000            90.00000
         0            58.10000            -6.70000             0.00000
         0            59.10000            -5.70000            90.00000
         0            59.10000            45.38197             0.00000
         0            59.65279            46.27639           -63.43495
         0            60.54721            46.72361             0.00000
         0            61.10000            47.61803            63.43495
         0            61.10000            52.38197             0.00000
         0            60.54721            53.27639            63.43495
         0            59.65279            53.72361             0.00000
         0            59.10000            54.61803           -63.43495
         0            59.10000            89.00000             0.00000
         0            58.10000            90.00000            90.00000
         0            43.70000            90.00000             0.00000
         0            42.70000            89.00000            90.00000
         0            42.70000            72.72076             0.00000
         0            42.01623            71.77208           -71.56505
         0            40.38377            71.22792             0.00000
         0            39.70000            70.27924            71.56505
         0            39.70000            65.72076             0.00000
         0            40.38377            64.77208            71.56505
         0            42.01623            64.22792             0.00000
         0            42.70000            63.27924           -71.56505
         0            42.70000            34.91421             0.00000
         0            42.40711            34.20711           -45.00000
         0            34.99289            26.79289             0.00000
         0            34.28579            26.50000           -45.00000
         0            24.81421            26.50000             0.00000
         0            24.10711            26.79289           -45.00000
         0            16.69289            34.20711             0.00000
         0            16.40000            34.91421           -45.00000
         0            16.40000            63.27924             0.00000
         0            17.08377            64.22792           -71.56505
         0            18.71623            64.77208             0.00000
         0            19.40000            65.72076            71.56505
         0            19.40000            70.27924             0.00000
         0            18.71623            71.22792            71.56505
         0            17.08377            71.77208             0.00000
         0            16.40000            72.72076           -71.56505
         0            16.40000            89.00000             0.00000
         0            15.40000            90.00000            90.00000
         0             1.00000            90.00000             0.00000
         0             0.00000            89.00000            90.00000
         0             0.00000            54.72076             0.00000
         0            -0.68377            53.77208           -71.56505
         0            -2.31623            53.22792             0.00000
         0            -3.00000            52.27924            71.56505
         0            -3.00000            47.72076             0.00000
         0            -2.31623            46.77208            71.56505
         0            -0.68377            46.22792             0.00000
         0             0.00000            45.27924           -71.56505
         0             0.00000            -5.70000             0.00000
         0             1.00000            -6.70000            90.00000
         0             7.38500            -6.70000             0.00000
         0             7.88500            -6.20000            90.00000
         1            32.35000            20.00000             0.00000
         1            26.75000            20.00000          -180.00000
         1            32.35000            20.00000          -180.00000
         2            49.17500             1.30000             0.00000
         2            47.82500             1.30000          -180.00000
         2            49.17500             1.30000          -180.00000
         3            11.27500             1.30000             0.00000
         3             9.92500             1.30000          -180.00000
         3            11.27500             1.30000          -180.00000
.END_BOARD_OUTLINE
.DRILLED_HOLES
.END_DRILLED_HOLES
.PLACEMENT
020_F0948_0029 020_F0948_0029 CN1           
29.55000       1.30000        0.00000        180.00000      TOP       PLACED         
022_40001_00B1 022_40001_00B1 SW1           
8.20000        79.50000       0.00000        0.00000        TOP       PLACED         
022_40001_00B1 022_40001_00B1 SW2           
48.90000       79.50000       0.00000        0.00000        TOP       PLACED         
062_40001_0521 062_40001_0521 SW3           
8.20000        35.00000       -0.00000       0.00000        TOP       PLACED         
062_40001_0521 062_40001_0521 SW4           
48.90000       35.00000       -0.00000       0.00000        TOP       PLACED         
022_10005_0D41 022_10005_0D41 USB1          
8.20000        60.00000       0.00000        90.00000       TOP       PLACED         
022_10005_0D41 022_10005_0D41 USB2          
48.90000       60.00000       0.00000        90.00000       TOP       PLACED         
086_2AT24_04R6 086_2AT24_04R6 SCW1          
29.55000       20.00000       0.00000        90.00000       TOP       PLACED         
006_03870_0140 006_03870_0140 LED1          
8.20000        44.00000       -0.00000       90.00000       TOP       PLACED         
006_03870_0140 006_03870_0140 LED2          
47.90000       44.00000       -0.00000       90.00000       TOP       PLACED         
.END_PLACEMENT
